#ISCELL
  pure_quanta quanta_title_block_c *
  *
#ISCELL
  standard offpage *
  page220_i1
#CELL
  pure_quanta q_res *
  page220_i11
#ISCELL
  standard offpage *
  page220_i12
#ISCELL
  standard offpage *
  page220_i13
#ISCELL
  standard offpage *
  page220_i14
#ISCELL
  standard offpage *
  page220_i15
#CELL
  pure_quanta q_res *
  page220_i16
#CELL
  pure_quanta q_res *
  page220_i17
#CELL
  pure_quanta q_res *
  page220_i18
#CELL
  pure_quanta q_res *
  page220_i19
#ISCELL
  standard offpage *
  page220_i2
#CELL
  pure_quanta q_res *
  page220_i20
#CELL
  pure_quanta q_res *
  page220_i21
#ISCELL
  standard offpage *
  page220_i22
#ISCELL
  standard offpage *
  page220_i23
#ISCELL
  standard offpage *
  page220_i24
#ISCELL
  standard offpage *
  page220_i25
#CELL
  pure_quanta q_res *
  page220_i26
#CELL
  pure_quanta q_res *
  page220_i3
#CELL
  pure_quanta q_res *
  page220_i4
#ISCELL
  standard offpage *
  page220_i7
#ISCELL
  standard offpage *
  page220_i8
